(kicad_pcb
	(version 20260206)
	(generator "pcbnew")
	(generator_version "10.0")
	(general
		(thickness 1.6)
		(legacy_teardrops no)
	)
	(paper "A4")
	(title_block
		(title "Wiwynn_Tioga_Pass_MB.brd")
		(comment 1 "Tioga Pass / footprint 343 of 4770 (JA9G1), pads 1-17 of 17")
	)
	(layers
		(0 "F.Cu" signal "TOP")
		(4 "In1.Cu" signal "L2GND")
		(6 "In2.Cu" signal "L3")
		(8 "In3.Cu" signal "L4GND")
		(10 "In4.Cu" signal "L5")
		(12 "In5.Cu" signal "L6GND")
		(14 "In6.Cu" signal "L7VCC")
		(16 "In7.Cu" signal "L8VCC")
		(18 "In8.Cu" signal "L9GND")
		(20 "In9.Cu" signal "L10")
		(22 "In10.Cu" signal "L11GND")
		(24 "In11.Cu" signal "L12")
		(26 "In12.Cu" signal "L13GND")
		(2 "B.Cu" signal "BOTTOM")
		(9 "F.Adhes" user "F.Adhesive")
		(11 "B.Adhes" user "B.Adhesive")
		(13 "F.Paste" user "Package Geometry/Pastemask Top")
		(15 "B.Paste" user "Package Geometry/Pastemask Bottom")
		(5 "F.SilkS" user "Ref Des/Silkscreen Top")
		(7 "B.SilkS" user "Ref Des/Silkscreen Bottom")
		(1 "F.Mask" user "Board Geometry/Soldermask Top")
		(3 "B.Mask" user "Board Geometry/Soldermask Bottom")
		(17 "Dwgs.User" user "User.Drawings")
		(19 "Cmts.User" user "User.Comments")
		(21 "Eco1.User" user "User.Eco1")
		(23 "Eco2.User" user "User.Eco2")
		(25 "Edge.Cuts" user "Board Geometry/Outline")
		(27 "Margin" user)
		(31 "F.CrtYd" user "Package Geometry/Place Bound Top")
		(29 "B.CrtYd" user "Package Geometry/Place Bound Bottom")
		(35 "F.Fab" user "Ref Des/Assembly Top")
		(33 "B.Fab" user "Ref Des/Assembly Bottom")
	)
	(footprint ""
		(layer "F.Cu")
		(at 496.000024 -5.500116 90)
		(property "Reference" "JA9G1"
			(at 0 0 90)
			(layer "F.SilkS")
			(hide yes)
			(effects
				(font
					(size 1.27 1.27)
				)
			)
		)
		(property "Value" "*"
			(at 12.1031 -6.0325 90)
			(unlocked yes)
			(layer "F.Fab")
			(hide yes)
			(effects
				(font
					(size 1.27 1.016)
					(thickness 0.1524)
				)
			)
		)
		(property "Device Type" "SKT-RJ45-LED-XFOR-1-GP_SOCKET-A"
			(at 12.1031 -7.5565 90)
			(unlocked yes)
			(layer "F.Fab")
			(hide yes)
			(effects
				(font
					(size 1.27 1.016)
					(thickness 0.1524)
				)
			)
		)
		(duplicate_pad_numbers_are_jumpers no)
		(pad "1" thru_hole rect
			(at 9.299956 0 90)
			(size 1.4986 4.3942)
			(drill oval 0.508 1.8034
				(offset -0.0508 0)
			)
			(layers "*.Cu" "*.Mask")
			(remove_unused_layers no)
			(net "GND")
			(clearance 0.0127)
			(thermal_gap 0.0127)
			(padstack
				(mode front_inner_back)
				(layer "Inner"
					(shape oval)
					(size 1.2192 2.5146)
					(clearance 0.1524)
				)
				(layer "B.Cu"
					(shape oval)
					(size 1.2192 2.5146)
					(clearance 0.1524)
				)
			)
		)
		(pad "2" thru_hole rect
			(at -9.299956 0 90)
			(size 1.4986 4.3942)
			(drill oval 0.508 1.8034
				(offset 0.0508 0)
			)
			(layers "*.Cu" "*.Mask")
			(remove_unused_layers no)
			(net "GND")
			(clearance 0.0127)
			(thermal_gap 0.0127)
			(padstack
				(mode front_inner_back)
				(layer "Inner"
					(shape oval)
					(size 1.2192 2.5146)
					(clearance 0.1524)
				)
				(layer "B.Cu"
					(shape oval)
					(size 1.2192 2.5146)
					(clearance 0.1524)
				)
			)
		)
		(pad "L1" thru_hole circle
			(at 7.104888 -13.159994 90)
			(size 1.3208 1.3208)
			(drill 0.9144)
			(layers "*.Cu" "*.Mask")
			(remove_unused_layers no)
			(net "LED_LAN_2_R_N")
			(clearance 0.1524)
			(thermal_gap 0.1524)
		)
		(pad "L2" thru_hole circle
			(at 6.089904 -14.429994 90)
			(size 1.3208 1.3208)
			(drill 0.9144)
			(layers "*.Cu" "*.Mask")
			(remove_unused_layers no)
			(net "LED_LAN_0_R_N")
			(clearance 0.1524)
			(thermal_gap 0.1524)
		)
		(pad "L3" thru_hole circle
			(at -6.089904 -14.429994 90)
			(size 1.3208 1.3208)
			(drill 0.9144)
			(layers "*.Cu" "*.Mask")
			(remove_unused_layers no)
			(net "LED_LAN_1_R_N")
			(clearance 0.1524)
			(thermal_gap 0.1524)
		)
		(pad "L4" thru_hole circle
			(at -7.104888 -13.159994 90)
			(size 1.3208 1.3208)
			(drill 0.9144)
			(layers "*.Cu" "*.Mask")
			(remove_unused_layers no)
			(net "NIC_LED_ACT_ANODE_R")
			(clearance 0.1524)
			(thermal_gap 0.1524)
		)
		(pad "R1" thru_hole circle
			(at 5.07492 -13.159994 90)
			(size 1.3208 1.3208)
			(drill 0.9144)
			(layers "*.Cu" "*.Mask")
			(remove_unused_layers no)
			(net "GND_LAN_TRCT1234_C")
			(clearance 0.1524)
			(thermal_gap 0.1524)
		)
		(pad "R2" thru_hole circle
			(at 4.059936 -14.429994 90)
			(size 1.3208 1.3208)
			(drill 0.9144)
			(layers "*.Cu" "*.Mask")
			(remove_unused_layers no)
			(net "NIC_MDI_SPRV_RJ45_0_R_DP")
			(clearance 0.1524)
			(thermal_gap 0.1524)
		)
		(pad "R3" thru_hole circle
			(at 3.044952 -13.159994 90)
			(size 1.3208 1.3208)
			(drill 0.9144)
			(layers "*.Cu" "*.Mask")
			(remove_unused_layers no)
			(net "NIC_MDI_SPRV_RJ45_0_R_DN")
			(clearance 0.1524)
			(thermal_gap 0.1524)
		)
		(pad "R4" thru_hole circle
			(at 2.029968 -14.429994 90)
			(size 1.3208 1.3208)
			(drill 0.9144)
			(layers "*.Cu" "*.Mask")
			(remove_unused_layers no)
			(net "NIC_MDI_SPRV_RJ45_1_R_DP")
			(clearance 0.1524)
			(thermal_gap 0.1524)
		)
		(pad "R5" thru_hole circle
			(at 1.014984 -13.159994 90)
			(size 1.3208 1.3208)
			(drill 0.9144)
			(layers "*.Cu" "*.Mask")
			(remove_unused_layers no)
			(net "NIC_MDI_SPRV_RJ45_1_R_DN")
			(clearance 0.1524)
			(thermal_gap 0.1524)
		)
		(pad "R6" thru_hole circle
			(at 0 -14.429994 90)
			(size 1.3208 1.3208)
			(drill 0.9144)
			(layers "*.Cu" "*.Mask")
			(remove_unused_layers no)
			(net "GND")
			(clearance 0.1524)
			(thermal_gap 0.1524)
		)
		(pad "R7" thru_hole circle
			(at -1.014984 -13.159994 90)
			(size 1.3208 1.3208)
			(drill 0.9144)
			(layers "*.Cu" "*.Mask")
			(remove_unused_layers no)
			(net "NIC_MDI_SPRV_RJ45_2_R_DP")
			(clearance 0.1524)
			(thermal_gap 0.1524)
		)
		(pad "R8" thru_hole circle
			(at -2.029968 -14.429994 90)
			(size 1.3208 1.3208)
			(drill 0.9144)
			(layers "*.Cu" "*.Mask")
			(remove_unused_layers no)
			(net "NIC_MDI_SPRV_RJ45_2_R_DN")
			(clearance 0.1524)
			(thermal_gap 0.1524)
		)
		(pad "R9" thru_hole circle
			(at -3.044952 -13.159994 90)
			(size 1.3208 1.3208)
			(drill 0.9144)
			(layers "*.Cu" "*.Mask")
			(remove_unused_layers no)
			(net "NIC_MDI_SPRV_RJ45_3_R_DP")
			(clearance 0.1524)
			(thermal_gap 0.1524)
		)
		(pad "R10" thru_hole circle
			(at -4.059936 -14.429994 90)
			(size 1.3208 1.3208)
			(drill 0.9144)
			(layers "*.Cu" "*.Mask")
			(remove_unused_layers no)
			(net "NIC_MDI_SPRV_RJ45_3_R_DN")
			(clearance 0.1524)
			(thermal_gap 0.1524)
		)
		(pad "R11" thru_hole circle
			(at -5.07492 -13.159994 90)
			(size 1.3208 1.3208)
			(drill 0.9144)
			(layers "*.Cu" "*.Mask")
			(remove_unused_layers no)
			(net "GND_LAN_TRCT1234_C")
			(clearance 0.1524)
			(thermal_gap 0.1524)
		)
	)
)
